# BASEBOARD_FAB2 (Tioga Pass) — schematic netlist excerpt (pin names and nets, part order shuffled) for the footprints in the layout excerpt that follows; sources: Cadence DE-HDL packaged netlist, KiCad conversion of Wiwynn_Tioga_Pass_MB.brd

EU8F2  ICS9FGP204  IC  pkg MLFP  page 101
  GND(0)  = GND
  VDD96  = P3V3_STBY_MNG
  DOT96SST  = TP_CLK_96M_CKMNG_P
  DOT96SSC  = TP_CLK_96M_CKMNG_N
  OE_96  = PD_CKMNG_OE
  OE_CPU  = PD_CKMNG_OE
  CPUCLKT0  = TP_CLK_100M_R_DP
  CPUCLKC0  = TP_CLK_100M_R_DN
  VDDCPU  = P3V3_STBY_MNG_CPU
  GNDCPU  = GND
  IREF  = A_COMP_CKMNG
  VDD32K  = P3V3_STBY_MNG
  \32khz\  = CLK_32K_SUSCLK_PLD_R
  GND32K  = GND
  VDDREF  = P3V3_STBY_MNG
  \25mhz_0\  = CLK_25M_BMC_R
  \25mhz_1\  = CLK_25M_CPLD_R
  GNDREF  = GND
  X1_25  = XTAL_CK_MNG_IN
  X2_25  = XTAL_CK_MNG_OUT_R
  GND33  = GND
  \33mhz_smbadr\  = PU_33P_33M_SMBADR
  VDD33  = P3V3_STBY_MNG
  RMII(5)  = TP_CLK5_50M_CKMNG
  RMII(4)  = CLK_50M_CKMNG_PCH_10GBE_R
  VDDRMII(0)  = P3V3_STBY_MNG_RMII
  GNDRMII(0)  = GND
  RMII(3)  = CLK_50M_CKMNG_SPRVLLE_R
  RMII(2)  = CLK_50M_CKMNG_BMC_2_R
  GNDRMII(1)  = GND
  VDDRMII(1)  = P3V3_STBY_MNG_RMII
  RMII(1)  = CLK_50M_CKMNG_BMC_1_R
  RMII(0)  = CLK_50M_CKMNG_OCP_R
  VDD_RGMII  = P3V3_STBY_MNG_RGMII
  GND_RGMII  = GND
  RGMII(1)  = TP_CLK_125M
  RGMII(0)  = TP_CLK_125M_BMCA
  SMBCLK  = SMB_HOST_STBY_LVC3_SCL_R4
  SMBDAT  = SMB_HOST_STBY_LVC3_SDA_R4
  VTTPWR_GD_PD_N  = PWRGD_P3V3_STBY
  GND(1)  = GND

(kicad_pcb
	(version 20260206)
	(generator "pcbnew")
	(generator_version "10.0")
	(general
		(thickness 1.6)
		(legacy_teardrops no)
	)
	(paper "A4")
	(title_block
		(title "Wiwynn_Tioga_Pass_MB.brd")
		(comment 1 "Tioga Pass / footprint 997 of 4770 (EU8F2), pads 1-17 of 41")
	)
	(layers
		(0 "F.Cu" signal "TOP")
		(4 "In1.Cu" signal "L2GND")
		(6 "In2.Cu" signal "L3")
		(8 "In3.Cu" signal "L4GND")
		(10 "In4.Cu" signal "L5")
		(12 "In5.Cu" signal "L6GND")
		(14 "In6.Cu" signal "L7VCC")
		(16 "In7.Cu" signal "L8VCC")
		(18 "In8.Cu" signal "L9GND")
		(20 "In9.Cu" signal "L10")
		(22 "In10.Cu" signal "L11GND")
		(24 "In11.Cu" signal "L12")
		(26 "In12.Cu" signal "L13GND")
		(2 "B.Cu" signal "BOTTOM")
		(9 "F.Adhes" user "F.Adhesive")
		(11 "B.Adhes" user "B.Adhesive")
		(13 "F.Paste" user "Package Geometry/Pastemask Top")
		(15 "B.Paste" user "Package Geometry/Pastemask Bottom")
		(5 "F.SilkS" user "Ref Des/Silkscreen Top")
		(7 "B.SilkS" user "Ref Des/Silkscreen Bottom")
		(1 "F.Mask" user "Board Geometry/Soldermask Top")
		(3 "B.Mask" user "Board Geometry/Soldermask Bottom")
		(17 "Dwgs.User" user "User.Drawings")
		(19 "Cmts.User" user "User.Comments")
		(21 "Eco1.User" user "User.Eco1")
		(23 "Eco2.User" user "User.Eco2")
		(25 "Edge.Cuts" user "Board Geometry/Outline")
		(27 "Margin" user)
		(31 "F.CrtYd" user "Package Geometry/Place Bound Top")
		(29 "B.CrtYd" user "Package Geometry/Place Bound Bottom")
		(35 "F.Fab" user "Ref Des/Assembly Top")
		(33 "B.Fab" user "Ref Des/Assembly Bottom")
	)
	(footprint ""
		(layer "F.Cu")
		(at 475.64802 -27.7495 90)
		(property "Reference" "EU8F2"
			(at 8.88365 7.29996 180)
			(unlocked yes)
			(layer "F.SilkS")
			(effects
				(font
					(size 0.7874 0.5842)
					(thickness 0.1524)
				)
			)
		)
		(property "Value" ""
			(at 0 0 90)
			(layer "F.Fab")
			(effects
				(font
					(size 1.27 1.27)
				)
			)
		)
		(duplicate_pad_numbers_are_jumpers no)
		(pad "1" smd custom
			(at 0 0 90)
			(size 0.0762 0.0762)
			(layers "F.Cu" "F.Mask" "F.Paste")
			(net "GND")
			(options
				(clearance outline)
				(anchor circle)
			)
			(primitives
				(gr_poly
					(pts
						(xy -0.5715 -0.1524)
						(arc
							(start 0.4191 -0.1524)
							(mid 0.5715 0)
							(end 0.4191 0.1524)
						)
						(xy -0.5715 0.1524)
					)
					(width 0)
					(fill yes)
				)
			)
		)
		(pad "2" smd custom
			(at 0 0.50038 90)
			(size 0.0762 0.0762)
			(layers "F.Cu" "F.Mask" "F.Paste")
			(net "P3V3_STBY_MNG")
			(options
				(clearance outline)
				(anchor circle)
			)
			(primitives
				(gr_poly
					(pts
						(xy -0.5715 -0.1524)
						(arc
							(start 0.4191 -0.1524)
							(mid 0.5715 0)
							(end 0.4191 0.1524)
						)
						(xy -0.5715 0.1524)
					)
					(width 0)
					(fill yes)
				)
			)
		)
		(pad "3" smd custom
			(at 0 1.00076 90)
			(size 0.0762 0.0762)
			(layers "F.Cu" "F.Mask" "F.Paste")
			(net "TP_CLK_96M_CKMNG_P")
			(options
				(clearance outline)
				(anchor circle)
			)
			(primitives
				(gr_poly
					(pts
						(xy -0.5715 -0.1524)
						(arc
							(start 0.4191 -0.1524)
							(mid 0.5715 0)
							(end 0.4191 0.1524)
						)
						(xy -0.5715 0.1524)
					)
					(width 0)
					(fill yes)
				)
			)
		)
		(pad "4" smd custom
			(at 0 1.50114 90)
			(size 0.0762 0.0762)
			(layers "F.Cu" "F.Mask" "F.Paste")
			(net "TP_CLK_96M_CKMNG_N")
			(options
				(clearance outline)
				(anchor circle)
			)
			(primitives
				(gr_poly
					(pts
						(xy -0.5715 -0.1524)
						(arc
							(start 0.4191 -0.1524)
							(mid 0.5715 0)
							(end 0.4191 0.1524)
						)
						(xy -0.5715 0.1524)
					)
					(width 0)
					(fill yes)
				)
			)
		)
		(pad "5" smd custom
			(at 0 2.00152 90)
			(size 0.0762 0.0762)
			(layers "F.Cu" "F.Mask" "F.Paste")
			(net "PD_CKMNG_OE")
			(options
				(clearance outline)
				(anchor circle)
			)
			(primitives
				(gr_poly
					(pts
						(xy -0.5715 -0.1524)
						(arc
							(start 0.4191 -0.1524)
							(mid 0.5715 0)
							(end 0.4191 0.1524)
						)
						(xy -0.5715 0.1524)
					)
					(width 0)
					(fill yes)
				)
			)
		)
		(pad "6" smd custom
			(at 0 2.5019 90)
			(size 0.0762 0.0762)
			(layers "F.Cu" "F.Mask" "F.Paste")
			(net "PD_CKMNG_OE")
			(options
				(clearance outline)
				(anchor circle)
			)
			(primitives
				(gr_poly
					(pts
						(xy -0.5715 -0.1524)
						(arc
							(start 0.4191 -0.1524)
							(mid 0.5715 0)
							(end 0.4191 0.1524)
						)
						(xy -0.5715 0.1524)
					)
					(width 0)
					(fill yes)
				)
			)
		)
		(pad "7" smd custom
			(at 0 3.00228 90)
			(size 0.0762 0.0762)
			(layers "F.Cu" "F.Mask" "F.Paste")
			(net "TP_CLK_100M_R_DP")
			(options
				(clearance outline)
				(anchor circle)
			)
			(primitives
				(gr_poly
					(pts
						(xy -0.5715 -0.1524)
						(arc
							(start 0.4191 -0.1524)
							(mid 0.5715 0)
							(end 0.4191 0.1524)
						)
						(xy -0.5715 0.1524)
					)
					(width 0)
					(fill yes)
				)
			)
		)
		(pad "8" smd custom
			(at 0 3.50266 90)
			(size 0.0762 0.0762)
			(layers "F.Cu" "F.Mask" "F.Paste")
			(net "TP_CLK_100M_R_DN")
			(options
				(clearance outline)
				(anchor circle)
			)
			(primitives
				(gr_poly
					(pts
						(xy -0.5715 -0.1524)
						(arc
							(start 0.4191 -0.1524)
							(mid 0.5715 0)
							(end 0.4191 0.1524)
						)
						(xy -0.5715 0.1524)
					)
					(width 0)
					(fill yes)
				)
			)
		)
		(pad "9" smd custom
			(at 0 4.00304 90)
			(size 0.0762 0.0762)
			(layers "F.Cu" "F.Mask" "F.Paste")
			(net "P3V3_STBY_MNG_CPU")
			(options
				(clearance outline)
				(anchor circle)
			)
			(primitives
				(gr_poly
					(pts
						(xy -0.5715 -0.1524)
						(arc
							(start 0.4191 -0.1524)
							(mid 0.5715 0)
							(end 0.4191 0.1524)
						)
						(xy -0.5715 0.1524)
					)
					(width 0)
					(fill yes)
				)
			)
		)
		(pad "10" smd custom
			(at 0 4.50342 90)
			(size 0.0762 0.0762)
			(layers "F.Cu" "F.Mask" "F.Paste")
			(net "GND")
			(options
				(clearance outline)
				(anchor circle)
			)
			(primitives
				(gr_poly
					(pts
						(xy -0.5715 -0.1524)
						(arc
							(start 0.4191 -0.1524)
							(mid 0.5715 0)
							(end 0.4191 0.1524)
						)
						(xy -0.5715 0.1524)
					)
					(width 0)
					(fill yes)
				)
			)
		)
		(pad "11" smd custom
			(at 0.85852 5.36448 90)
			(size 0.0762 0.0762)
			(layers "F.Cu" "F.Mask" "F.Paste")
			(net "A_COMP_CKMNG")
			(options
				(clearance outline)
				(anchor circle)
			)
			(primitives
				(gr_poly
					(pts
						(xy -0.1524 0.5715)
						(arc
							(start -0.1524 -0.4191)
							(mid 0 -0.5715)
							(end 0.1524 -0.4191)
						)
						(xy 0.1524 0.5715)
					)
					(width 0)
					(fill yes)
				)
			)
		)
		(pad "12" smd custom
			(at 1.3589 5.36448 90)
			(size 0.0762 0.0762)
			(layers "F.Cu" "F.Mask" "F.Paste")
			(net "P3V3_STBY_MNG")
			(options
				(clearance outline)
				(anchor circle)
			)
			(primitives
				(gr_poly
					(pts
						(xy -0.1524 0.5715)
						(arc
							(start -0.1524 -0.4191)
							(mid 0 -0.5715)
							(end 0.1524 -0.4191)
						)
						(xy 0.1524 0.5715)
					)
					(width 0)
					(fill yes)
				)
			)
		)
		(pad "13" smd custom
			(at 1.85928 5.36448 90)
			(size 0.0762 0.0762)
			(layers "F.Cu" "F.Mask" "F.Paste")
			(net "CLK_32K_SUSCLK_PLD_R")
			(options
				(clearance outline)
				(anchor circle)
			)
			(primitives
				(gr_poly
					(pts
						(xy -0.1524 0.5715)
						(arc
							(start -0.1524 -0.4191)
							(mid 0 -0.5715)
							(end 0.1524 -0.4191)
						)
						(xy 0.1524 0.5715)
					)
					(width 0)
					(fill yes)
				)
			)
		)
		(pad "14" smd custom
			(at 2.35966 5.36448 90)
			(size 0.0762 0.0762)
			(layers "F.Cu" "F.Mask" "F.Paste")
			(net "GND")
			(options
				(clearance outline)
				(anchor circle)
			)
			(primitives
				(gr_poly
					(pts
						(xy -0.1524 0.5715)
						(arc
							(start -0.1524 -0.4191)
							(mid 0 -0.5715)
							(end 0.1524 -0.4191)
						)
						(xy 0.1524 0.5715)
					)
					(width 0)
					(fill yes)
				)
			)
		)
		(pad "15" smd custom
			(at 2.86004 5.36448 90)
			(size 0.0762 0.0762)
			(layers "F.Cu" "F.Mask" "F.Paste")
			(net "P3V3_STBY_MNG")
			(options
				(clearance outline)
				(anchor circle)
			)
			(primitives
				(gr_poly
					(pts
						(xy -0.1524 0.5715)
						(arc
							(start -0.1524 -0.4191)
							(mid 0 -0.5715)
							(end 0.1524 -0.4191)
						)
						(xy 0.1524 0.5715)
					)
					(width 0)
					(fill yes)
				)
			)
		)
		(pad "16" smd custom
			(at 3.36042 5.36448 90)
			(size 0.0762 0.0762)
			(layers "F.Cu" "F.Mask" "F.Paste")
			(net "CLK_25M_BMC_R")
			(options
				(clearance outline)
				(anchor circle)
			)
			(primitives
				(gr_poly
					(pts
						(xy -0.1524 0.5715)
						(arc
							(start -0.1524 -0.4191)
							(mid 0 -0.5715)
							(end 0.1524 -0.4191)
						)
						(xy 0.1524 0.5715)
					)
					(width 0)
					(fill yes)
				)
			)
		)
		(pad "17" smd custom
			(at 3.8608 5.36448 90)
			(size 0.0762 0.0762)
			(layers "F.Cu" "F.Mask" "F.Paste")
			(net "CLK_25M_CPLD_R")
			(options
				(clearance outline)
				(anchor circle)
			)
			(primitives
				(gr_poly
					(pts
						(xy -0.1524 0.5715)
						(arc
							(start -0.1524 -0.4191)
							(mid 0 -0.5715)
							(end 0.1524 -0.4191)
						)
						(xy 0.1524 0.5715)
					)
					(width 0)
					(fill yes)
				)
			)
		)
	)
)
